(kicad_pcb
	(version 20221018)
	(generator pcbnew)
	(general
    (thickness 1.62)
  )
	(paper "A4")
	(title_block
    (title "ECP5 - Datacenter Secure Control Module (DC-SCM)")
    (date "2024-07-01")
    (rev "1.2.1")
		(comment 9 "footprints 229-237 of 506")
	)
	(layers
    (0 "F.Cu" signal)
    (1 "In1.Cu" power)
    (2 "In2.Cu" signal)
    (3 "In3.Cu" power)
    (4 "In4.Cu" power)
    (5 "In5.Cu" signal)
    (6 "In6.Cu" power)
    (31 "B.Cu" signal)
    (32 "B.Adhes" user "B.Adhesive")
    (33 "F.Adhes" user "F.Adhesive")
    (34 "B.Paste" user)
    (35 "F.Paste" user)
    (36 "B.SilkS" user "B.Silkscreen")
    (37 "F.SilkS" user "F.Silkscreen")
    (38 "B.Mask" user)
    (39 "F.Mask" user)
    (40 "Dwgs.User" user "User.Drawings")
    (41 "Cmts.User" user "User.Comments")
    (42 "Eco1.User" user "User.Eco1")
    (43 "Eco2.User" user "User.Eco2")
    (44 "Edge.Cuts" user)
    (45 "Margin" user)
    (46 "B.CrtYd" user "B.Courtyard")
    (47 "F.CrtYd" user "F.Courtyard")
    (48 "B.Fab" user)
    (49 "F.Fab" user)
  )
	(footprint "antmicro-footprints:R_0402_1005Metric" (layer "B.Cu")
    (at 64.25 89.95 180)
    (descr "Resistor SMD 0402")
    (tags "resistor SMD 0402")
    (property "Author" "Antmicro")
    (property "License" "Apache-2.0")
    (property "MPN" "CR0402-FX-1001GLF")
    (property "Manufacturer" "Bourns")
    (property "Public" "False")
    (property "Sheetfile" "power-supply.kicad_sch")
    (property "Sheetname" "Power supply")
    (property "Tolerance" "1%")
    (property "Val" "1k")
    (property "ki_description" "SMD Chip Resistor, 1 kohm, ± 1%, 63 mW, 0402 [1005 Metric], Thick Film, General Purpose")
    (property "ki_keywords" "0402, SMT, RESISTOR, PASSIVE")
    (attr smd)
    (fp_text reference "R112" (at -1.67 -0.925 270) (layer "B.SilkS")
        (effects (font (size 0.7 0.7) (thickness 0.127)) (justify mirror))
    )
    (fp_text value "R_1k_0402" (at 0 -1.17 180) (layer "B.Fab")
        (effects (font (size 1 1) (thickness 0.15)) (justify mirror))
    )
    (fp_text user "License: Apache-2.0" (at -0.95 -5.169) (layer "B.Fab") hide
        (effects (font (size 0.7 0.7) (thickness 0.15)) (justify left bottom mirror))
    )
    (fp_text user "Author: Antmicro" (at -0.95 -4.169) (layer "B.Fab") hide
        (effects (font (size 0.7 0.7) (thickness 0.15)) (justify left bottom mirror))
    )
    (fp_text user "${REFERENCE}" (at 0 0 180) (layer "B.Fab")
        (effects (font (size 0.25 0.25) (thickness 0.04)) (justify mirror))
    )
    (fp_rect (start -0.925 0.47) (end 0.925 -0.47)
      (stroke (width 0.05) (type default)) (fill none) (layer "B.CrtYd"))
    (fp_rect (start -0.5 0.25) (end 0.5 -0.25)
      (stroke (width 0.15) (type solid)) (fill none) (layer "B.Fab"))
    (pad "1" smd roundrect (at -0.48 0 180) (size 0.59 0.64) (layers "B.Cu" "B.Paste" "B.Mask") (roundrect_rratio 0.25)
      (net 399 "Net-(Q15-D)") (pintype "passive"))
    (pad "2" smd roundrect (at 0.48 0 180) (size 0.59 0.64) (layers "B.Cu" "B.Paste" "B.Mask") (roundrect_rratio 0.25)
      (net 346 "Net-(D12-A)") (pintype "passive"))
  )
	(footprint "antmicro-footprints:R_0402_1005Metric" (layer "B.Cu")
    (at 64.25 88.35 180)
    (descr "Resistor SMD 0402")
    (tags "resistor SMD 0402")
    (property "Author" "Antmicro")
    (property "License" "Apache-2.0")
    (property "MPN" "CR0402-FX-1001GLF")
    (property "Manufacturer" "Bourns")
    (property "Public" "False")
    (property "Sheetfile" "power-supply.kicad_sch")
    (property "Sheetname" "Power supply")
    (property "Tolerance" "1%")
    (property "Val" "1k")
    (property "ki_description" "SMD Chip Resistor, 1 kohm, ± 1%, 63 mW, 0402 [1005 Metric], Thick Film, General Purpose")
    (property "ki_keywords" "0402, SMT, RESISTOR, PASSIVE")
    (attr smd)
    (fp_text reference "R113" (at -0.41 0.805 180) (layer "B.SilkS")
        (effects (font (size 0.7 0.7) (thickness 0.127)) (justify mirror))
    )
    (fp_text value "R_1k_0402" (at 0 -1.17 180) (layer "B.Fab")
        (effects (font (size 1 1) (thickness 0.15)) (justify mirror))
    )
    (fp_text user "Author: Antmicro" (at -0.95 -4.169) (layer "B.Fab") hide
        (effects (font (size 0.7 0.7) (thickness 0.15)) (justify left bottom mirror))
    )
    (fp_text user "${REFERENCE}" (at 0 0 180) (layer "B.Fab")
        (effects (font (size 0.25 0.25) (thickness 0.04)) (justify mirror))
    )
    (fp_text user "License: Apache-2.0" (at -0.95 -5.169) (layer "B.Fab") hide
        (effects (font (size 0.7 0.7) (thickness 0.15)) (justify left bottom mirror))
    )
    (fp_rect (start -0.925 0.47) (end 0.925 -0.47)
      (stroke (width 0.05) (type default)) (fill none) (layer "B.CrtYd"))
    (fp_rect (start -0.5 0.25) (end 0.5 -0.25)
      (stroke (width 0.15) (type solid)) (fill none) (layer "B.Fab"))
    (pad "1" smd roundrect (at -0.48 0 180) (size 0.59 0.64) (layers "B.Cu" "B.Paste" "B.Mask") (roundrect_rratio 0.25)
      (net 400 "Net-(Q16-D)") (pintype "passive"))
    (pad "2" smd roundrect (at 0.48 0 180) (size 0.59 0.64) (layers "B.Cu" "B.Paste" "B.Mask") (roundrect_rratio 0.25)
      (net 347 "Net-(D13-A)") (pintype "passive"))
  )
	(footprint "antmicro-footprints:R_0402_1005Metric" (layer "B.Cu")
    (at 74.2 87.55 180)
    (descr "Resistor SMD 0402")
    (tags "resistor SMD 0402")
    (property "Author" "Antmicro")
    (property "License" "Apache-2.0")
    (property "MPN" "CR0402-FX-1002GLF")
    (property "Manufacturer" "Bourns")
    (property "Public" "False")
    (property "Sheetfile" "power-supply.kicad_sch")
    (property "Sheetname" "Power supply")
    (property "Tolerance" "1%")
    (property "Val" "10k")
    (property "ki_description" "SMD Chip Resistor, 10 kohm, ± 1%, 62.5 mW, 0402 [1005 Metric], Thick Film, General Purpose")
    (property "ki_keywords" "0402, SMT, RESISTOR, PASSIVE")
    (attr smd)
    (fp_text reference "R106" (at -0.15 1.17 180) (layer "B.SilkS")
        (effects (font (size 0.7 0.7) (thickness 0.127)) (justify mirror))
    )
    (fp_text value "R_10k_0402" (at 0 -1.17 180) (layer "B.Fab")
        (effects (font (size 1 1) (thickness 0.15)) (justify mirror))
    )
    (fp_text user "${REFERENCE}" (at 0 0 180) (layer "B.Fab")
        (effects (font (size 0.25 0.25) (thickness 0.04)) (justify mirror))
    )
    (fp_text user "License: Apache-2.0" (at -0.95 -5.169) (layer "B.Fab") hide
        (effects (font (size 0.7 0.7) (thickness 0.15)) (justify left bottom mirror))
    )
    (fp_text user "Author: Antmicro" (at -0.95 -4.169) (layer "B.Fab") hide
        (effects (font (size 0.7 0.7) (thickness 0.15)) (justify left bottom mirror))
    )
    (fp_rect (start -0.925 0.47) (end 0.925 -0.47)
      (stroke (width 0.05) (type default)) (fill none) (layer "B.CrtYd"))
    (fp_rect (start -0.5 0.25) (end 0.5 -0.25)
      (stroke (width 0.15) (type solid)) (fill none) (layer "B.Fab"))
    (pad "1" smd roundrect (at -0.48 0 180) (size 0.59 0.64) (layers "B.Cu" "B.Paste" "B.Mask") (roundrect_rratio 0.25)
      (net 11 "VCC5V0") (pintype "passive"))
    (pad "2" smd roundrect (at 0.48 0 180) (size 0.59 0.64) (layers "B.Cu" "B.Paste" "B.Mask") (roundrect_rratio 0.25)
      (net 224 "/Power supply/1V35_PG") (pintype "passive"))
  )
	(footprint "antmicro-footprints:R_0402_1005Metric" (layer "B.Cu")
    (at 97.05 88 -90)
    (descr "Resistor SMD 0402")
    (tags "resistor SMD 0402")
    (property "Author" "Antmicro")
    (property "License" "Apache-2.0")
    (property "MPN" "CR0402-FX-1001GLF")
    (property "Manufacturer" "Bourns")
    (property "Public" "False")
    (property "Sheetfile" "ethernet.kicad_sch")
    (property "Sheetname" "Ethernet")
    (property "Tolerance" "1%")
    (property "Val" "1k")
    (property "ki_description" "SMD Chip Resistor, 1 kohm, ± 1%, 63 mW, 0402 [1005 Metric], Thick Film, General Purpose")
    (property "ki_keywords" "0402, SMT, RESISTOR, PASSIVE")
    (attr smd)
    (fp_text reference "R15" (at -2.03 -0.05 90) (layer "B.SilkS")
        (effects (font (size 0.7 0.7) (thickness 0.127)) (justify mirror))
    )
    (fp_text value "R_1k_0402" (at 0 -1.17 90) (layer "B.Fab")
        (effects (font (size 1 1) (thickness 0.15)) (justify mirror))
    )
    (fp_text user "${REFERENCE}" (at 0 0 90) (layer "B.Fab")
        (effects (font (size 0.25 0.25) (thickness 0.04)) (justify mirror))
    )
    (fp_text user "License: Apache-2.0" (at -0.95 -5.169 90) (layer "B.Fab") hide
        (effects (font (size 0.7 0.7) (thickness 0.15)) (justify left bottom mirror))
    )
    (fp_text user "Author: Antmicro" (at -0.95 -4.169 90) (layer "B.Fab") hide
        (effects (font (size 0.7 0.7) (thickness 0.15)) (justify left bottom mirror))
    )
    (fp_rect (start -0.925 0.47) (end 0.925 -0.47)
      (stroke (width 0.05) (type default)) (fill none) (layer "B.CrtYd"))
    (fp_rect (start -0.5 0.25) (end 0.5 -0.25)
      (stroke (width 0.15) (type solid)) (fill none) (layer "B.Fab"))
    (pad "1" smd roundrect (at -0.48 0 270) (size 0.59 0.64) (layers "B.Cu" "B.Paste" "B.Mask") (roundrect_rratio 0.25)
      (net 681 "Net-(J1-Pad15)") (pintype "passive"))
    (pad "2" smd roundrect (at 0.48 0 270) (size 0.59 0.64) (layers "B.Cu" "B.Paste" "B.Mask") (roundrect_rratio 0.25)
      (net 165 "/Ethernet/ETH_LED2") (pintype "passive"))
  )
	(footprint "antmicro-footprints:R_0402_1005Metric" (layer "B.Cu")
    (at 115.7 136.75 180)
    (descr "Resistor SMD 0402")
    (tags "resistor SMD 0402")
    (property "Author" "Antmicro")
    (property "Current" "1A")
    (property "License" "Apache-2.0")
    (property "MPN" "ERJ2GE0R00X")
    (property "Manufacturer" "Panasonic")
    (property "Public" "False")
    (property "Sheetfile" "edge-connector.kicad_sch")
    (property "Sheetname" "Edge connector")
    (property "Tolerance" "")
    (property "Val" "0R")
    (property "ki_description" "SMD Chip Resistor, Jumper, 0 ohm, 100 mW, 0402 [1005 Metric], Thick Film, General Purpose")
    (property "ki_keywords" "0402, SMT, RESISTOR, PASSIVE")
    (attr smd)
    (fp_text reference "R47" (at 0.02 -1.185 180) (layer "B.SilkS")
        (effects (font (size 0.7 0.7) (thickness 0.127)) (justify mirror))
    )
    (fp_text value "R_0R_0402" (at 0 -1.17 180) (layer "B.Fab")
        (effects (font (size 1 1) (thickness 0.15)) (justify mirror))
    )
    (fp_text user "Author: Antmicro" (at -0.95 -4.169) (layer "B.Fab") hide
        (effects (font (size 0.7 0.7) (thickness 0.15)) (justify left bottom mirror))
    )
    (fp_text user "License: Apache-2.0" (at -0.95 -5.169) (layer "B.Fab") hide
        (effects (font (size 0.7 0.7) (thickness 0.15)) (justify left bottom mirror))
    )
    (fp_text user "${REFERENCE}" (at 0 0 180) (layer "B.Fab")
        (effects (font (size 0.25 0.25) (thickness 0.04)) (justify mirror))
    )
    (fp_rect (start -0.925 0.47) (end 0.925 -0.47)
      (stroke (width 0.05) (type default)) (fill none) (layer "B.CrtYd"))
    (fp_rect (start -0.5 0.25) (end 0.5 -0.25)
      (stroke (width 0.15) (type solid)) (fill none) (layer "B.Fab"))
    (pad "1" smd roundrect (at -0.48 0 180) (size 0.59 0.64) (layers "B.Cu" "B.Paste" "B.Mask") (roundrect_rratio 0.25)
      (net 277 "SGPIO1_CLK") (pintype "passive"))
    (pad "2" smd roundrect (at 0.48 0 180) (size 0.59 0.64) (layers "B.Cu" "B.Paste" "B.Mask") (roundrect_rratio 0.25)
      (net 83 "SGPIO0_CLK") (pintype "passive"))
  )
	(footprint "antmicro-footprints:R_0402_1005Metric" (layer "B.Cu")
    (at 86.4 135.6 90)
    (descr "Resistor SMD 0402")
    (tags "resistor SMD 0402")
    (property "Author" "Antmicro")
    (property "Current" "1A")
    (property "DNP" "DNP")
    (property "License" "Apache-2.0")
    (property "MPN" "ERJ2GE0R00X")
    (property "Manufacturer" "Panasonic")
    (property "Public" "False")
    (property "Sheetfile" "fpga-banks.kicad_sch")
    (property "Sheetname" "FPGA banks")
    (property "Tolerance" "")
    (property "Val" "0R")
    (property "dnp" "")
    (property "exclude_from_bom" "")
    (property "ki_description" "SMD Chip Resistor, Jumper, 0 ohm, 100 mW, 0402 [1005 Metric], Thick Film, General Purpose")
    (property "ki_keywords" "0402, SMT, RESISTOR, PASSIVE")
    (attr smd exclude_from_pos_files exclude_from_bom)
    (fp_text reference "R132" (at -2.35 0.02 90) (layer "B.SilkS")
        (effects (font (size 0.7 0.7) (thickness 0.127)) (justify mirror))
    )
    (fp_text value "R_0R_0402" (at 0 -1.17 90) (layer "B.Fab")
        (effects (font (size 1 1) (thickness 0.15)) (justify mirror))
    )
    (fp_text user "License: Apache-2.0" (at -0.95 -5.169 270) (layer "B.Fab") hide
        (effects (font (size 0.7 0.7) (thickness 0.15)) (justify left bottom mirror))
    )
    (fp_text user "${REFERENCE}" (at 0 0 90) (layer "B.Fab")
        (effects (font (size 0.25 0.25) (thickness 0.04)) (justify mirror))
    )
    (fp_text user "Author: Antmicro" (at -0.95 -4.169 270) (layer "B.Fab") hide
        (effects (font (size 0.7 0.7) (thickness 0.15)) (justify left bottom mirror))
    )
    (fp_rect (start -0.925 0.47) (end 0.925 -0.47)
      (stroke (width 0.05) (type default)) (fill none) (layer "B.CrtYd"))
    (fp_rect (start -0.5 0.25) (end 0.5 -0.25)
      (stroke (width 0.15) (type solid)) (fill none) (layer "B.Fab"))
    (pad "1" smd roundrect (at -0.48 0 90) (size 0.59 0.64) (layers "B.Cu" "B.Paste" "B.Mask") (roundrect_rratio 0.25)
      (net 54 "SPI0_CLK") (pintype "passive"))
    (pad "2" smd roundrect (at 0.48 0 90) (size 0.59 0.64) (layers "B.Cu" "B.Paste" "B.Mask") (roundrect_rratio 0.25)
      (net 427 "Net-(U21I-PB4A)") (pintype "passive"))
  )
	(footprint "antmicro-footprints:C_0603_1608Metric" (layer "B.Cu")
    (at 88.7 98.6 90)
    (descr "Capacitor SMD 0603")
    (tags "capacitor 0603")
    (property "Author" "Antmicro")
    (property "Dielectric" "")
    (property "License" "Apache-2.0")
    (property "MPN" "GRM188R60J226MEA0D")
    (property "Manufacturer" "Murata")
    (property "Public" "False")
    (property "Sheetfile" "interfaces.kicad_sch")
    (property "Sheetname" "Interfaces")
    (property "Val" "22u")
    (property "Voltage" "")
    (property "ki_description" "SMD Multilayer Ceramic Capacitor, 22 µF, 6.3 V, 0603 [1608 Metric], ± 20%, X5R, GRM Series")
    (property "ki_keywords" "0603, SMT, CAPACITOR, PASSIVE, CERAMIC, MLCC")
    (attr smd)
    (fp_text reference "C49" (at -0.075 -1.06 90) (layer "B.SilkS")
        (effects (font (size 0.7 0.7) (thickness 0.127)) (justify mirror))
    )
    (fp_text value "C_22u_0603" (at 0 -1.9 90) (layer "B.Fab")
        (effects (font (size 1 1) (thickness 0.15)) (justify mirror))
    )
    (fp_text user "License: Apache-2.0" (at -1.682 -5.895 270) (layer "B.Fab") hide
        (effects (font (size 0.7 0.7) (thickness 0.15)) (justify left bottom mirror))
    )
    (fp_text user "${REFERENCE}" (at -1.682 -3.895 270) (layer "B.Fab") hide
        (effects (font (size 0.7 0.7) (thickness 0.15)) (justify left bottom mirror))
    )
    (fp_text user "Author: Antmicro" (at -1.682 -4.894 270) (layer "B.Fab") hide
        (effects (font (size 0.7 0.7) (thickness 0.15)) (justify left bottom mirror))
    )
    (fp_line (start -0.15 -0.4) (end 0.15 -0.4)
      (stroke (width 0.15) (type solid)) (layer "B.SilkS"))
    (fp_line (start -0.15 0.4) (end 0.15 0.4)
      (stroke (width 0.15) (type solid)) (layer "B.SilkS"))
    (fp_rect (start -1.25 0.65) (end 1.25 -0.65)
      (stroke (width 0.05) (type solid)) (fill none) (layer "B.CrtYd"))
    (fp_rect (start -0.8 0.4) (end 0.8 -0.4)
      (stroke (width 0.15) (type solid)) (fill none) (layer "B.Fab"))
    (pad "1" smd roundrect (at -0.7 0 90) (size 0.8 1) (layers "B.Cu" "B.Paste" "B.Mask") (roundrect_rratio 0.2)
      (net 1 "GND") (pintype "passive"))
    (pad "2" smd roundrect (at 0.7 0 90) (size 0.8 1) (layers "B.Cu" "B.Paste" "B.Mask") (roundrect_rratio 0.2)
      (net 2 "VCC3V3") (pintype "passive"))
  )
	(footprint "antmicro-footprints:R_0402_1005Metric" (layer "B.Cu")
    (at 88.7 95.7)
    (descr "Resistor SMD 0402")
    (tags "resistor SMD 0402")
    (property "Author" "Antmicro")
    (property "License" "Apache-2.0")
    (property "MPN" "CR0402-FX-4702GLF")
    (property "Manufacturer" "Bourns")
    (property "Public" "False")
    (property "Sheetfile" "interfaces.kicad_sch")
    (property "Sheetname" "Interfaces")
    (property "Tolerance" "1%")
    (property "Val" "47k")
    (property "ki_description" "SMD Chip Resistor, 47 kohm, ± 1%, 62.5 mW, 0402 [1005 Metric], Thick Film, General Purpose")
    (property "ki_keywords" "0402, SMT, RESISTOR, PASSIVE")
    (attr smd)
    (fp_text reference "R68" (at 0 -2.2) (layer "B.SilkS")
        (effects (font (size 0.7 0.7) (thickness 0.127)) (justify mirror))
    )
    (fp_text value "R_47k_0402" (at 0 -1.17) (layer "B.Fab")
        (effects (font (size 1 1) (thickness 0.15)) (justify mirror))
    )
    (fp_text user "Author: Antmicro" (at -0.95 -4.169 180) (layer "B.Fab") hide
        (effects (font (size 0.7 0.7) (thickness 0.15)) (justify left bottom mirror))
    )
    (fp_text user "License: Apache-2.0" (at -0.95 -5.169 180) (layer "B.Fab") hide
        (effects (font (size 0.7 0.7) (thickness 0.15)) (justify left bottom mirror))
    )
    (fp_text user "${REFERENCE}" (at 0 0) (layer "B.Fab")
        (effects (font (size 0.25 0.25) (thickness 0.04)) (justify mirror))
    )
    (fp_rect (start -0.925 0.47) (end 0.925 -0.47)
      (stroke (width 0.05) (type default)) (fill none) (layer "B.CrtYd"))
    (fp_rect (start -0.5 0.25) (end 0.5 -0.25)
      (stroke (width 0.15) (type solid)) (fill none) (layer "B.Fab"))
    (pad "1" smd roundrect (at -0.48 0) (size 0.59 0.64) (layers "B.Cu" "B.Paste" "B.Mask") (roundrect_rratio 0.25)
      (net 2 "VCC3V3") (pintype "passive"))
    (pad "2" smd roundrect (at 0.48 0) (size 0.59 0.64) (layers "B.Cu" "B.Paste" "B.Mask") (roundrect_rratio 0.25)
      (net 286 "MMC_DAT7") (pintype "passive"))
  )
	(footprint "antmicro-footprints:R_0402_1005Metric" (layer "B.Cu")
    (at 88.7 96.7)
    (descr "Resistor SMD 0402")
    (tags "resistor SMD 0402")
    (property "Author" "Antmicro")
    (property "License" "Apache-2.0")
    (property "MPN" "CR0402-FX-4702GLF")
    (property "Manufacturer" "Bourns")
    (property "Public" "False")
    (property "Sheetfile" "interfaces.kicad_sch")
    (property "Sheetname" "Interfaces")
    (property "Tolerance" "1%")
    (property "Val" "47k")
    (property "ki_description" "SMD Chip Resistor, 47 kohm, ± 1%, 62.5 mW, 0402 [1005 Metric], Thick Film, General Purpose")
    (property "ki_keywords" "0402, SMT, RESISTOR, PASSIVE")
    (attr smd)
    (fp_text reference "R66" (at 0 -2.3) (layer "B.SilkS")
        (effects (font (size 0.7 0.7) (thickness 0.127)) (justify mirror))
    )
    (fp_text value "R_47k_0402" (at 0 -1.17) (layer "B.Fab")
        (effects (font (size 1 1) (thickness 0.15)) (justify mirror))
    )
    (fp_text user "License: Apache-2.0" (at -0.95 -5.169 180) (layer "B.Fab") hide
        (effects (font (size 0.7 0.7) (thickness 0.15)) (justify left bottom mirror))
    )
    (fp_text user "Author: Antmicro" (at -0.95 -4.169 180) (layer "B.Fab") hide
        (effects (font (size 0.7 0.7) (thickness 0.15)) (justify left bottom mirror))
    )
    (fp_text user "${REFERENCE}" (at 0 0) (layer "B.Fab")
        (effects (font (size 0.25 0.25) (thickness 0.04)) (justify mirror))
    )
    (fp_rect (start -0.925 0.47) (end 0.925 -0.47)
      (stroke (width 0.05) (type default)) (fill none) (layer "B.CrtYd"))
    (fp_rect (start -0.5 0.25) (end 0.5 -0.25)
      (stroke (width 0.15) (type solid)) (fill none) (layer "B.Fab"))
    (pad "1" smd roundrect (at -0.48 0) (size 0.59 0.64) (layers "B.Cu" "B.Paste" "B.Mask") (roundrect_rratio 0.25)
      (net 2 "VCC3V3") (pintype "passive"))
    (pad "2" smd roundrect (at 0.48 0) (size 0.59 0.64) (layers "B.Cu" "B.Paste" "B.Mask") (roundrect_rratio 0.25)
      (net 284 "MMC_DAT5") (pintype "passive"))
  )
)
